(kicad_pcb
	(version 20260206)
	(generator "pcbnew")
	(generator_version "10.0")
	(general
		(thickness 1.6)
		(legacy_teardrops no)
	)
	(paper "A4")
	(title_block
		(title "pdpb — Lightning_PDPB_BRD.brd")
		(comment 1 "Lightning (Wiwynn / Facebook NVMe JBOF) / footprints 478-484 of 1140")
	)
	(layers
		(0 "F.Cu" signal "TOP")
		(4 "In1.Cu" signal "L2GND")
		(6 "In2.Cu" signal "L3")
		(8 "In3.Cu" signal "L4VCC")
		(10 "In4.Cu" signal "L5VCC")
		(12 "In5.Cu" signal "L6")
		(14 "In6.Cu" signal "L7GND")
		(2 "B.Cu" signal "BOTTOM")
		(9 "F.Adhes" user "F.Adhesive")
		(11 "B.Adhes" user "B.Adhesive")
		(13 "F.Paste" user "Package Geometry/Pastemask Top")
		(15 "B.Paste" user "Package Geometry/Pastemask Bottom")
		(5 "F.SilkS" user "Ref Des/Silkscreen Top")
		(7 "B.SilkS" user "Ref Des/Silkscreen Bottom")
		(1 "F.Mask" user "Board Geometry/Soldermask Top")
		(3 "B.Mask" user "Board Geometry/Soldermask Bottom")
		(17 "Dwgs.User" user "User.Drawings")
		(19 "Cmts.User" user "User.Comments")
		(21 "Eco1.User" user "User.Eco1")
		(23 "Eco2.User" user "User.Eco2")
		(25 "Edge.Cuts" user "Board Geometry/Outline")
		(27 "Margin" user)
		(31 "F.CrtYd" user "Package Geometry/Place Bound Top")
		(29 "B.CrtYd" user "Package Geometry/Place Bound Bottom")
		(35 "F.Fab" user "Ref Des/Assembly Top")
		(33 "B.Fab" user "Ref Des/Assembly Bottom")
	)
	(footprint ""
		(layer "F.Cu")
		(at 49.022 -453.644 -90)
		(property "Reference" "R9415"
			(at 0 0 270)
			(layer "F.SilkS")
			(hide yes)
			(effects
				(font
					(size 1.27 1.27)
				)
			)
		)
		(property "Value" "100R2J-2-GP"
			(at 0.064008 -3.993896 270)
			(unlocked yes)
			(layer "F.Fab")
			(hide yes)
			(effects
				(font
					(size 1.016 1.016)
					(thickness 0.1524)
				)
			)
		)
		(property "Device Type" "R402H14"
			(at 0.064008 -5.517896 270)
			(unlocked yes)
			(layer "F.Fab")
			(hide yes)
			(effects
				(font
					(size 1.016 1.016)
					(thickness 0.1524)
				)
			)
		)
		(duplicate_pad_numbers_are_jumpers no)
		(fp_line
			(start -0.508 -0.9398)
			(end -0.508 0.9398)
			(stroke
				(width 0.1524)
				(type default)
			)
			(layer "F.SilkS")
		)
		(fp_line
			(start 0.508 -0.9398)
			(end -0.508 -0.9398)
			(stroke
				(width 0.1524)
				(type default)
			)
			(layer "F.SilkS")
		)
		(fp_rect
			(start -0.508 0.9398)
			(end 0.508 -0.9398)
			(stroke
				(width 0)
				(type default)
			)
			(fill no)
			(layer "F.CrtYd")
		)
		(fp_rect
			(start -0.508 0.9398)
			(end 0.508 -0.9398)
			(stroke
				(width 0)
				(type default)
			)
			(fill no)
			(layer "F.Fab")
		)
		(pad "1" smd custom
			(at 0 -0.4445 270)
			(size 0.1397 0.1397)
			(layers "F.Cu" "F.Mask" "F.Paste")
			(net "P3V3")
			(options
				(clearance outline)
				(anchor circle)
			)
			(primitives
				(gr_poly
					(pts
						(arc
							(start -0.1778 -0.2794)
							(mid -0.249642 -0.249642)
							(end -0.2794 -0.1778)
						)
						(arc
							(start -0.2794 0.1778)
							(mid -0.249642 0.249642)
							(end -0.1778 0.2794)
						)
						(arc
							(start 0.1778 0.2794)
							(mid 0.249642 0.249642)
							(end 0.2794 0.1778)
						)
						(arc
							(start 0.2794 -0.1778)
							(mid 0.249642 -0.249642)
							(end 0.1778 -0.2794)
						)
					)
					(width 0)
					(fill yes)
				)
			)
		)
		(pad "2" smd custom
			(at 0 0.4445 270)
			(size 0.1397 0.1397)
			(layers "F.Cu" "F.Mask" "F.Paste")
			(net "DRV_ACT_5")
			(options
				(clearance outline)
				(anchor circle)
			)
			(primitives
				(gr_poly
					(pts
						(arc
							(start -0.1778 -0.2794)
							(mid -0.249642 -0.249642)
							(end -0.2794 -0.1778)
						)
						(arc
							(start -0.2794 0.1778)
							(mid -0.249642 0.249642)
							(end -0.1778 0.2794)
						)
						(arc
							(start 0.1778 0.2794)
							(mid 0.249642 0.249642)
							(end 0.2794 0.1778)
						)
						(arc
							(start 0.2794 -0.1778)
							(mid 0.249642 -0.249642)
							(end 0.1778 -0.2794)
						)
					)
					(width 0)
					(fill yes)
				)
			)
		)
	)
	(footprint ""
		(layer "F.Cu")
		(at 8.7376 -462.2038 90)
		(property "Reference" "PC1169"
			(at 0 0 90)
			(layer "F.SilkS")
			(hide yes)
			(effects
				(font
					(size 1.27 1.27)
				)
			)
		)
		(property "Value" "SCD01U50V2KX-1GP"
			(at 1.1811 -2.7051 90)
			(unlocked yes)
			(layer "F.Fab")
			(hide yes)
			(effects
				(font
					(size 1.016 1.016)
					(thickness 0.1524)
				)
			)
		)
		(property "Device Type" "C402H22"
			(at 1.1811 -4.2291 90)
			(unlocked yes)
			(layer "F.Fab")
			(hide yes)
			(effects
				(font
					(size 1.016 1.016)
					(thickness 0.1524)
				)
			)
		)
		(duplicate_pad_numbers_are_jumpers no)
		(fp_rect
			(start -0.4318 0.9525)
			(end 0.4318 -0.9525)
			(stroke
				(width 0)
				(type default)
			)
			(fill no)
			(layer "F.CrtYd")
		)
		(fp_rect
			(start -0.4318 0.9525)
			(end 0.4318 -0.9525)
			(stroke
				(width 0)
				(type default)
			)
			(fill no)
			(layer "F.Fab")
		)
		(pad "1" smd custom
			(at 0 -0.4445 90)
			(size 0.1524 0.1524)
			(layers "F.Cu" "F.Mask" "F.Paste")
			(net "P12V")
			(options
				(clearance outline)
				(anchor circle)
			)
			(primitives
				(gr_poly
					(pts
						(arc
							(start 0.3048 -0.2032)
							(mid 0.275042 -0.275042)
							(end 0.2032 -0.3048)
						)
						(arc
							(start -0.2032 -0.3048)
							(mid -0.275042 -0.275042)
							(end -0.3048 -0.2032)
						)
						(arc
							(start -0.3048 0.2032)
							(mid -0.275042 0.275042)
							(end -0.2032 0.3048)
						)
						(arc
							(start 0.2032 0.3048)
							(mid 0.275042 0.275042)
							(end 0.3048 0.2032)
						)
					)
					(width 0)
					(fill yes)
				)
			)
		)
		(pad "2" smd custom
			(at 0 0.4445 90)
			(size 0.1524 0.1524)
			(layers "F.Cu" "F.Mask" "F.Paste")
			(net "GND")
			(options
				(clearance outline)
				(anchor circle)
			)
			(primitives
				(gr_poly
					(pts
						(arc
							(start 0.3048 -0.2032)
							(mid 0.275042 -0.275042)
							(end 0.2032 -0.3048)
						)
						(arc
							(start -0.2032 -0.3048)
							(mid -0.275042 -0.275042)
							(end -0.3048 -0.2032)
						)
						(arc
							(start -0.3048 0.2032)
							(mid -0.275042 0.275042)
							(end -0.2032 0.3048)
						)
						(arc
							(start 0.2032 0.3048)
							(mid 0.275042 0.275042)
							(end 0.3048 0.2032)
						)
					)
					(width 0)
					(fill yes)
				)
			)
		)
	)
	(footprint ""
		(layer "F.Cu")
		(at 78.9686 -105.7148 -90)
		(property "Reference" "C8935"
			(at 0 0 270)
			(layer "F.SilkS")
			(hide yes)
			(effects
				(font
					(size 1.27 1.27)
				)
			)
		)
		(property "Value" "SC10U25V3MX-GP"
			(at 0 -2.8194 270)
			(unlocked yes)
			(layer "F.Fab")
			(hide yes)
			(effects
				(font
					(size 1.016 1.016)
					(thickness 0.1524)
				)
			)
		)
		(property "Device Type" "C603H40"
			(at 0 -4.3434 270)
			(unlocked yes)
			(layer "F.Fab")
			(hide yes)
			(effects
				(font
					(size 1.016 1.016)
					(thickness 0.1524)
				)
			)
		)
		(duplicate_pad_numbers_are_jumpers no)
		(fp_line
			(start 0.508 0)
			(end -0.508 0)
			(stroke
				(width 0.2032)
				(type default)
			)
			(layer "F.SilkS")
		)
		(fp_rect
			(start -0.5842 1.3335)
			(end 0.5842 -1.3335)
			(stroke
				(width 0)
				(type default)
			)
			(fill no)
			(layer "F.CrtYd")
		)
		(fp_rect
			(start -0.5842 1.3335)
			(end 0.5842 -1.3335)
			(stroke
				(width 0)
				(type default)
			)
			(fill no)
			(layer "F.Fab")
		)
		(pad "1" smd custom
			(at 0 -0.762 270)
			(size 0.2159 0.2159)
			(layers "F.Cu" "F.Mask" "F.Paste")
			(net "VDD_DIFF_4")
			(options
				(clearance outline)
				(anchor circle)
			)
			(primitives
				(gr_poly
					(pts
						(arc
							(start -0.3302 -0.4318)
							(mid -0.402042 -0.402042)
							(end -0.4318 -0.3302)
						)
						(arc
							(start -0.4318 0.3302)
							(mid -0.402042 0.402042)
							(end -0.3302 0.4318)
						)
						(arc
							(start 0.3302 0.4318)
							(mid 0.402042 0.402042)
							(end 0.4318 0.3302)
						)
						(arc
							(start 0.4318 -0.3302)
							(mid 0.402042 -0.402042)
							(end 0.3302 -0.4318)
						)
					)
					(width 0)
					(fill yes)
				)
			)
		)
		(pad "2" smd custom
			(at 0 0.762 270)
			(size 0.2159 0.2159)
			(layers "F.Cu" "F.Mask" "F.Paste")
			(net "GND")
			(options
				(clearance outline)
				(anchor circle)
			)
			(primitives
				(gr_poly
					(pts
						(arc
							(start -0.3302 -0.4318)
							(mid -0.402042 -0.402042)
							(end -0.4318 -0.3302)
						)
						(arc
							(start -0.4318 0.3302)
							(mid -0.402042 0.402042)
							(end -0.3302 0.4318)
						)
						(arc
							(start 0.3302 0.4318)
							(mid 0.402042 0.402042)
							(end 0.4318 0.3302)
						)
						(arc
							(start 0.4318 -0.3302)
							(mid 0.402042 -0.402042)
							(end 0.3302 -0.4318)
						)
					)
					(width 0)
					(fill yes)
				)
			)
		)
	)
	(footprint ""
		(layer "F.Cu")
		(at 95.504 -296.545)
		(property "Reference" "R9078"
			(at 0 0 0)
			(layer "F.SilkS")
			(hide yes)
			(effects
				(font
					(size 1.27 1.27)
				)
			)
		)
		(property "Value" "27R2F-GP"
			(at 0.064008 -3.993896 0)
			(unlocked yes)
			(layer "F.Fab")
			(hide yes)
			(effects
				(font
					(size 1.016 1.016)
					(thickness 0.1524)
				)
			)
		)
		(property "Device Type" "R402H16"
			(at 0.064008 -5.517896 0)
			(unlocked yes)
			(layer "F.Fab")
			(hide yes)
			(effects
				(font
					(size 1.016 1.016)
					(thickness 0.1524)
				)
			)
		)
		(duplicate_pad_numbers_are_jumpers no)
		(fp_line
			(start -0.508 -0.9398)
			(end -0.508 0.9398)
			(stroke
				(width 0.1524)
				(type default)
			)
			(layer "F.SilkS")
		)
		(fp_line
			(start 0.508 -0.9398)
			(end -0.508 -0.9398)
			(stroke
				(width 0.1524)
				(type default)
			)
			(layer "F.SilkS")
		)
		(fp_rect
			(start -0.508 0.9398)
			(end 0.508 -0.9398)
			(stroke
				(width 0)
				(type default)
			)
			(fill no)
			(layer "F.CrtYd")
		)
		(fp_rect
			(start -0.508 0.9398)
			(end 0.508 -0.9398)
			(stroke
				(width 0)
				(type default)
			)
			(fill no)
			(layer "F.Fab")
		)
		(pad "1" smd custom
			(at 0 -0.4445)
			(size 0.1397 0.1397)
			(layers "F.Cu" "F.Mask" "F.Paste")
			(net "PE_CLK_100M_DR2_2_R_P")
			(options
				(clearance outline)
				(anchor circle)
			)
			(primitives
				(gr_poly
					(pts
						(arc
							(start -0.1778 -0.2794)
							(mid -0.249642 -0.249642)
							(end -0.2794 -0.1778)
						)
						(arc
							(start -0.2794 0.1778)
							(mid -0.249642 0.249642)
							(end -0.1778 0.2794)
						)
						(arc
							(start 0.1778 0.2794)
							(mid 0.249642 0.249642)
							(end 0.2794 0.1778)
						)
						(arc
							(start 0.2794 -0.1778)
							(mid 0.249642 -0.249642)
							(end 0.1778 -0.2794)
						)
					)
					(width 0)
					(fill yes)
				)
			)
		)
		(pad "2" smd custom
			(at 0 0.4445)
			(size 0.1397 0.1397)
			(layers "F.Cu" "F.Mask" "F.Paste")
			(net "PE_CLK100M_DR2_2_P")
			(options
				(clearance outline)
				(anchor circle)
			)
			(primitives
				(gr_poly
					(pts
						(arc
							(start -0.1778 -0.2794)
							(mid -0.249642 -0.249642)
							(end -0.2794 -0.1778)
						)
						(arc
							(start -0.2794 0.1778)
							(mid -0.249642 0.249642)
							(end -0.1778 0.2794)
						)
						(arc
							(start 0.1778 0.2794)
							(mid 0.249642 0.249642)
							(end 0.2794 0.1778)
						)
						(arc
							(start 0.2794 -0.1778)
							(mid 0.249642 -0.249642)
							(end 0.1778 -0.2794)
						)
					)
					(width 0)
					(fill yes)
				)
			)
		)
	)
	(footprint ""
		(layer "F.Cu")
		(at 98.679 -202.184)
		(property "Reference" "R9086"
			(at 0 0 0)
			(layer "F.SilkS")
			(hide yes)
			(effects
				(font
					(size 1.27 1.27)
				)
			)
		)
		(property "Value" "27R2F-GP"
			(at 0.064008 -3.993896 0)
			(unlocked yes)
			(layer "F.Fab")
			(hide yes)
			(effects
				(font
					(size 1.016 1.016)
					(thickness 0.1524)
				)
			)
		)
		(property "Device Type" "R402H16"
			(at 0.064008 -5.517896 0)
			(unlocked yes)
			(layer "F.Fab")
			(hide yes)
			(effects
				(font
					(size 1.016 1.016)
					(thickness 0.1524)
				)
			)
		)
		(duplicate_pad_numbers_are_jumpers no)
		(fp_line
			(start -0.508 -0.9398)
			(end -0.508 0.9398)
			(stroke
				(width 0.1524)
				(type default)
			)
			(layer "F.SilkS")
		)
		(fp_line
			(start 0.508 -0.9398)
			(end -0.508 -0.9398)
			(stroke
				(width 0.1524)
				(type default)
			)
			(layer "F.SilkS")
		)
		(fp_rect
			(start -0.508 0.9398)
			(end 0.508 -0.9398)
			(stroke
				(width 0)
				(type default)
			)
			(fill no)
			(layer "F.CrtYd")
		)
		(fp_rect
			(start -0.508 0.9398)
			(end 0.508 -0.9398)
			(stroke
				(width 0)
				(type default)
			)
			(fill no)
			(layer "F.Fab")
		)
		(pad "1" smd custom
			(at 0 -0.4445)
			(size 0.1397 0.1397)
			(layers "F.Cu" "F.Mask" "F.Paste")
			(net "PE_CLK_100M_DR4_1_R_N")
			(options
				(clearance outline)
				(anchor circle)
			)
			(primitives
				(gr_poly
					(pts
						(arc
							(start -0.1778 -0.2794)
							(mid -0.249642 -0.249642)
							(end -0.2794 -0.1778)
						)
						(arc
							(start -0.2794 0.1778)
							(mid -0.249642 0.249642)
							(end -0.1778 0.2794)
						)
						(arc
							(start 0.1778 0.2794)
							(mid 0.249642 0.249642)
							(end 0.2794 0.1778)
						)
						(arc
							(start 0.2794 -0.1778)
							(mid 0.249642 -0.249642)
							(end 0.1778 -0.2794)
						)
					)
					(width 0)
					(fill yes)
				)
			)
		)
		(pad "2" smd custom
			(at 0 0.4445)
			(size 0.1397 0.1397)
			(layers "F.Cu" "F.Mask" "F.Paste")
			(net "PE_CLK100M_DR4_1_N")
			(options
				(clearance outline)
				(anchor circle)
			)
			(primitives
				(gr_poly
					(pts
						(arc
							(start -0.1778 -0.2794)
							(mid -0.249642 -0.249642)
							(end -0.2794 -0.1778)
						)
						(arc
							(start -0.2794 0.1778)
							(mid -0.249642 0.249642)
							(end -0.1778 0.2794)
						)
						(arc
							(start 0.1778 0.2794)
							(mid 0.249642 0.249642)
							(end 0.2794 0.1778)
						)
						(arc
							(start 0.2794 -0.1778)
							(mid 0.249642 -0.249642)
							(end 0.1778 -0.2794)
						)
					)
					(width 0)
					(fill yes)
				)
			)
		)
	)
	(footprint ""
		(layer "F.Cu")
		(at 26.416 -300.9646 -90)
		(property "Reference" "Q62"
			(at 0 0 270)
			(layer "F.SilkS")
			(hide yes)
			(effects
				(font
					(size 1.27 1.27)
				)
			)
		)
		(property "Value" "2N7002A-7-GP"
			(at 0.127 -8.9662 270)
			(unlocked yes)
			(layer "F.Fab")
			(hide yes)
			(effects
				(font
					(size 1.016 1.016)
					(thickness 0.1524)
				)
			)
		)
		(property "Device Type" "SOT23DGS2D4H48"
			(at 0.127 -10.4902 270)
			(unlocked yes)
			(layer "F.Fab")
			(hide yes)
			(effects
				(font
					(size 1.016 1.016)
					(thickness 0.1524)
				)
			)
		)
		(duplicate_pad_numbers_are_jumpers no)
		(fp_line
			(start -1.651 1.778)
			(end 1.651 1.778)
			(stroke
				(width 0.1524)
				(type default)
			)
			(layer "F.SilkS")
		)
		(fp_line
			(start 1.651 1.778)
			(end 1.651 -1.778)
			(stroke
				(width 0.1524)
				(type default)
			)
			(layer "F.SilkS")
		)
		(fp_line
			(start -1.651 -1.778)
			(end -1.651 1.778)
			(stroke
				(width 0.1524)
				(type default)
			)
			(layer "F.SilkS")
		)
		(fp_line
			(start 1.651 -1.778)
			(end -1.651 -1.778)
			(stroke
				(width 0.1524)
				(type default)
			)
			(layer "F.SilkS")
		)
		(fp_poly
			(pts
				(xy -1.778 1.8796) (xy -1.778 -1.8796) (xy 1.778 -1.8796) (xy 1.778 1.8796)
			)
			(stroke
				(width 0)
				(type default)
			)
			(fill no)
			(layer "F.CrtYd")
		)
		(fp_poly
			(pts
				(xy -1.778 1.8796) (xy -1.778 -1.8796) (xy 1.778 -1.8796) (xy 1.778 1.8796)
			)
			(stroke
				(width 0)
				(type default)
			)
			(fill no)
			(layer "F.Fab")
		)
		(pad "D" smd custom
			(at 0 -0.9525 270)
			(size 0.1905 0.1905)
			(layers "F.Cu" "F.Mask" "F.Paste")
			(net "P12V_MOST7_GATE")
			(options
				(clearance outline)
				(anchor circle)
			)
			(primitives
				(gr_poly
					(pts
						(arc
							(start -0.1778 0.5715)
							(mid -0.321484 0.511984)
							(end -0.381 0.3683)
						)
						(arc
							(start -0.381 -0.3683)
							(mid -0.321484 -0.511984)
							(end -0.1778 -0.5715)
						)
						(arc
							(start 0.1778 -0.5715)
							(mid 0.321484 -0.511984)
							(end 0.381 -0.3683)
						)
						(arc
							(start 0.381 0.3683)
							(mid 0.321484 0.511984)
							(end 0.1778 0.5715)
						)
					)
					(width 0)
					(fill yes)
				)
			)
		)
		(pad "G" smd custom
			(at -0.98425 0.9525 270)
			(size 0.1905 0.1905)
			(layers "F.Cu" "F.Mask" "F.Paste")
			(net "SSD7_PWREN_R")
			(options
				(clearance outline)
				(anchor circle)
			)
			(primitives
				(gr_poly
					(pts
						(arc
							(start -0.1778 0.5715)
							(mid -0.321484 0.511984)
							(end -0.381 0.3683)
						)
						(arc
							(start -0.381 -0.3683)
							(mid -0.321484 -0.511984)
							(end -0.1778 -0.5715)
						)
						(arc
							(start 0.1778 -0.5715)
							(mid 0.321484 -0.511984)
							(end 0.381 -0.3683)
						)
						(arc
							(start 0.381 0.3683)
							(mid 0.321484 0.511984)
							(end 0.1778 0.5715)
						)
					)
					(width 0)
					(fill yes)
				)
			)
		)
		(pad "S" smd custom
			(at 0.98425 0.9525 270)
			(size 0.1905 0.1905)
			(layers "F.Cu" "F.Mask" "F.Paste")
			(net "GND")
			(options
				(clearance outline)
				(anchor circle)
			)
			(primitives
				(gr_poly
					(pts
						(arc
							(start -0.1778 0.5715)
							(mid -0.321484 0.511984)
							(end -0.381 0.3683)
						)
						(arc
							(start -0.381 -0.3683)
							(mid -0.321484 -0.511984)
							(end -0.1778 -0.5715)
						)
						(arc
							(start 0.1778 -0.5715)
							(mid 0.321484 -0.511984)
							(end 0.381 -0.3683)
						)
						(arc
							(start 0.381 0.3683)
							(mid 0.321484 0.511984)
							(end 0.1778 0.5715)
						)
					)
					(width 0)
					(fill yes)
				)
			)
		)
	)
	(footprint ""
		(layer "F.Cu")
		(at 77.7748 -432.2445 180)
		(property "Reference" "R9961"
			(at 0 0 180)
			(layer "F.SilkS")
			(hide yes)
			(effects
				(font
					(size 1.27 1.27)
				)
			)
		)
		(property "Value" "56R2F-1-GP"
			(at 0.064008 -3.993896 180)
			(unlocked yes)
			(layer "F.Fab")
			(hide yes)
			(effects
				(font
					(size 1.016 1.016)
					(thickness 0.1524)
				)
			)
		)
		(property "Device Type" "R402H16"
			(at 0.064008 -5.517896 180)
			(unlocked yes)
			(layer "F.Fab")
			(hide yes)
			(effects
				(font
					(size 1.016 1.016)
					(thickness 0.1524)
				)
			)
		)
		(duplicate_pad_numbers_are_jumpers no)
		(fp_line
			(start 0.508 -0.9398)
			(end -0.508 -0.9398)
			(stroke
				(width 0.1524)
				(type default)
			)
			(layer "F.SilkS")
		)
		(fp_line
			(start -0.508 -0.9398)
			(end -0.508 0.9398)
			(stroke
				(width 0.1524)
				(type default)
			)
			(layer "F.SilkS")
		)
		(fp_rect
			(start -0.508 0.9398)
			(end 0.508 -0.9398)
			(stroke
				(width 0)
				(type default)
			)
			(fill no)
			(layer "F.CrtYd")
		)
		(fp_rect
			(start -0.508 0.9398)
			(end 0.508 -0.9398)
			(stroke
				(width 0)
				(type default)
			)
			(fill no)
			(layer "F.Fab")
		)
		(pad "1" smd custom
			(at 0 -0.4445 180)
			(size 0.1397 0.1397)
			(layers "F.Cu" "F.Mask" "F.Paste")
			(net "PE_100M_CLK4_P")
			(options
				(clearance outline)
				(anchor circle)
			)
			(primitives
				(gr_poly
					(pts
						(arc
							(start -0.1778 -0.2794)
							(mid -0.249642 -0.249642)
							(end -0.2794 -0.1778)
						)
						(arc
							(start -0.2794 0.1778)
							(mid -0.249642 0.249642)
							(end -0.1778 0.2794)
						)
						(arc
							(start 0.1778 0.2794)
							(mid 0.249642 0.249642)
							(end 0.2794 0.1778)
						)
						(arc
							(start 0.2794 -0.1778)
							(mid 0.249642 -0.249642)
							(end 0.1778 -0.2794)
						)
					)
					(width 0)
					(fill yes)
				)
			)
		)
		(pad "2" smd custom
			(at 0 0.4445 180)
			(size 0.1397 0.1397)
			(layers "F.Cu" "F.Mask" "F.Paste")
			(net "GND")
			(options
				(clearance outline)
				(anchor circle)
			)
			(primitives
				(gr_poly
					(pts
						(arc
							(start -0.1778 -0.2794)
							(mid -0.249642 -0.249642)
							(end -0.2794 -0.1778)
						)
						(arc
							(start -0.2794 0.1778)
							(mid -0.249642 0.249642)
							(end -0.1778 0.2794)
						)
						(arc
							(start 0.1778 0.2794)
							(mid 0.249642 0.249642)
							(end 0.2794 0.1778)
						)
						(arc
							(start 0.2794 -0.1778)
							(mid 0.249642 -0.249642)
							(end 0.1778 -0.2794)
						)
					)
					(width 0)
					(fill yes)
				)
			)
		)
	)
)
